M48
INCH,TZ
T01C.01
T02C.012
T03C.016
T04C.02
T05C.14
T06C.001
T07C.073
T08C.086
T09C.087
T10C.146
;LEADER: 12 
;HEADER: 
;CODE  : ASCII 
;FILE  : 15669-1-1-8.drl for board 15669-1.brd ... layers TOP and BOTTOM
;T01 Holesize 1. = 10.000000 Tolerance = +0.000000/-0.000000 PLATED MILS Quantity = 5804
;T02 Holesize 2. = 12.000000 Tolerance = +0.000000/-0.000000 PLATED MILS Quantity = 59
;T03 Holesize 3. = 16.000000 Tolerance = +0.000000/-0.000000 PLATED MILS Quantity = 135
;T04 Holesize 4. = 20.000000 Tolerance = +0.000000/-0.000000 PLATED MILS Quantity = 66
;T05 Holesize 5. = 140.000000 Tolerance = +0.000000/-0.000000 PLATED MILS Quantity = 2
;T06 Holesize 6. = 1.000000 Tolerance = +0.000000/-0.000000 NON_PLATED MILS Quantity = 11
;T07 Holesize 7. = 73.000000 Tolerance = +0.000000/-0.000000 NON_PLATED MILS Quantity = 30
;T08 Holesize 8. = 86.000000 Tolerance = +0.000000/-0.000000 NON_PLATED MILS Quantity = 8
;T09 Holesize 9. = 87.000000 Tolerance = +0.000000/-0.000000 NON_PLATED MILS Quantity = 6
;T10 Holesize 10. = 146.000000 Tolerance = +0.000000/-0.000000 NON_PLATED MILS Quantity = 2
%
G90
T01
X10018Y5500
X30018
X20000Y20000
X5500Y20982
X20000Y40000
X5500Y40982
X20000Y60000
X5500Y60982
X20000Y80000
X5500Y80982
X20000Y100000
X5500Y100982
X20000Y120000
X5500Y120982
X20000Y140000
X5500Y140982
X20000Y160000
X5500Y160982
X20000Y180000
X5500Y180982
X20000Y200000
X5500Y200982
X20000Y220000
X5500Y220982
X20000Y240000
X5500Y240982
Y260982
Y280982
Y300982
Y320982
X20000Y340000
X5500Y340982
Y360982
X27500Y380000
X20000
X5500Y380982
X20000Y400000
X5500Y400982
X20000Y420000
X5500Y420982
X20000Y440000
X27000
X5500Y440982
X20000Y460000
X5500Y460982
X20000Y480000
X5500Y480982
X20000Y500000
X5500Y500982
X20000Y520000
X5500Y520982
X27500Y540000
X20000
X5500Y540982
X27500Y553500
X16500Y598197
X24500Y599700
X27529Y601522
Y604722
X16500Y606166
X24500Y606544
X20000Y607620
Y610820
X24500Y612249
X16500Y612166
X27529Y614071
Y617271
X16500Y618765
X24500Y619093
X20000Y620218
Y623418
X16500Y624765
X24500Y624897
X27529Y626719
Y629919
X16500Y631363
X24500Y631741
X20000Y632817
Y636017
X16500Y637363
X24500Y637496
X27529Y639318
Y642518
X24500Y644340
X16500Y644530
X20000Y645415
Y648615
X16500Y649500
Y657000
X20000Y658013
Y661213
X16500Y662226
X24500Y662693
X27529Y664515
Y667715
X16500Y669158
X24500Y669537
X20000Y670612
Y673812
X16500Y675158
X24500Y675291
X27529Y677113
Y680313
X16500Y681757
X24500Y682135
X20000Y683210
Y686410
X16500Y687757
X24500Y687889
X27529Y689711
Y692911
X16500Y694355
X24500Y694733
X20000Y695809
Y699009
X16500Y700355
X24500Y700488
X27529Y702310
Y705510
X16500Y706953
X24500Y707332
X20000Y708407
Y711607
X24500Y712886
X16500Y712953
X27529Y714708
Y717908
X16500Y719552
X24500Y719730
X20000Y721006
Y724206
X24500Y725485
X16500Y725552
X27529Y727307
Y730507
X24500Y732329
X16500Y732500
X27699Y737535
X16500Y751658
X20000Y752502
Y755702
X16500Y757048
X24500Y756981
X27529Y758803
Y762003
X16500Y763646
X24500Y763825
X20000Y765100
Y768300
X16500Y769646
X24500Y769579
X27529Y771401
Y774601
X24500Y776423
X16500Y777725
Y785694
X20000Y787147
Y790347
X24500Y791626
X16500Y791694
X27529Y793448
Y796648
X16500Y798292
X24500Y798470
X20000Y799746
Y802946
X24500Y804225
X16500Y804292
X27529Y806047
Y809247
X16500Y810891
X24500Y811069
X20000Y812344
Y815544
X24500Y816823
X16500Y816891
X27529Y818645
Y821845
X16500Y823489
X24500Y823667
X20000Y824943
Y828143
X24500Y829422
X16500Y829489
X27529Y831244
Y834444
X16500Y836087
X24500Y836266
X20000Y837541
Y840741
X24500Y841820
X16500Y842087
X27529Y843642
Y846842
X16500Y848686
X24500Y848664
X20000Y850139
Y853339
X24500Y854419
X16500Y854686
X27529Y856241
Y859441
X24500Y861263
X16500Y861284
X20000Y862738
Y865938
X24500Y867017
X16500Y867284
X27529Y868839
Y872039
X24500Y873861
X16500Y873883
X20000Y875336
Y878536
X24500Y879665
X16500Y879883
X27529Y881487
Y884687
X24500Y886509
X16500Y889500
X34872Y890906
X24500Y892414
X27529Y894236
Y897436
X16500Y899079
X24500Y899258
X20000Y900533
Y903733
X24500Y905012
X16500Y905079
X27529Y906834
Y910034
X16500Y911678
X24500Y911856
X20000Y913132
Y916332
X16500Y917678
X34500Y925000
X16000Y931000
X20000Y940000
Y960000
X36000
X20000Y980000
X5500Y980299
X30000Y991000
X36500Y999500
X5500Y1000299
Y1020299
Y1040299
X23291Y1062791
X31707Y1086000
X16500Y1094260
X24500Y1095769
X27529Y1097585
Y1100785
X16500Y1102229
X24500Y1102601
X20000Y1103683
Y1106883
X16500Y1108229
X24500Y1108368
X27529Y1110184
Y1113384
X16500Y1114828
X24500Y1115200
X20000Y1116281
Y1119481
X16500Y1120828
X32335Y1122002
X37396Y1130912
X33971Y1131741
X24500Y1133365
X16500Y1133500
X27529Y1135181
Y1138381
X16500Y1140024
X24500Y1140197
X20000Y1141478
Y1144678
X16500Y1146024
X24500Y1145963
X27529Y1147779
Y1150979
X16500Y1152623
X24500Y1152795
X20000Y1154076
Y1157276
X24500Y1158562
X16500Y1158623
X27529Y1160378
Y1163578
X16500Y1165221
X24500Y1165394
X20000Y1166675
Y1169875
X16500Y1171221
X24500Y1171160
X27529Y1172976
Y1176176
X16500Y1177820
X24500Y1177992
X20000Y1179273
Y1182473
X24500Y1183758
X16500Y1183820
X27529Y1185574
Y1188774
X16500Y1190418
X24500Y1190590
X20000Y1191872
Y1195072
X24500Y1196357
X16500Y1196418
X27529Y1198173
Y1201373
X16500Y1203016
X24500Y1203189
X20000Y1204470
Y1207670
X16500Y1209016
X24500Y1208955
X27529Y1210771
Y1213971
X16500Y1215615
X24500Y1215787
X20000Y1217069
Y1220269
X16500Y1221615
X24500Y1221554
X27529Y1223370
Y1226570
X24500Y1228386
X16500Y1228500
X33201Y1230674
X32959Y1234478
X36000Y1236000
X16500Y1247721
X20000Y1248565
Y1251765
X24500Y1253050
X16500Y1253111
X27529Y1254866
Y1258066
X16500Y1259709
X24500Y1259882
X20000Y1261163
Y1264363
X24500Y1265648
X16500Y1265709
X27529Y1267464
Y1270664
X16500Y1272308
X24500Y1272480
X20000Y1273761
Y1276961
X24500Y1278247
X16500Y1278308
X27529Y1280063
Y1283263
X16500Y1284906
X24500Y1285079
X20000Y1286360
Y1289560
X24500Y1290845
X16500Y1290906
X27529Y1292661
Y1295861
X16500Y1297505
X24500Y1297677
X20000Y1298958
X33699Y1301782
X20000Y1302158
X16500Y1303505
X30000Y1305000
X26500Y1305121
X36170Y1308434
X30700Y1308600
X33938Y1311000
X38500
X16417Y1311583
X24500Y1313092
X27529Y1314908
Y1318108
X16500Y1319552
X24500Y1319924
X34000Y1321000
X20000Y1321006
Y1324206
X16500Y1325552
X24500Y1325691
X27529Y1327507
Y1330707
X16500Y1332150
X24500Y1332523
X20000Y1333604
Y1336804
X16500Y1338150
X24500Y1338289
X27529Y1340105
Y1343305
X16500Y1344749
X24500Y1345121
X20000Y1346202
Y1349402
X16500Y1350749
X24500Y1350888
X27529Y1352704
Y1355904
X16500Y1357347
X24500Y1357720
X20000Y1358801
Y1362001
X24500Y1363286
X16500Y1363347
X27529Y1365102
Y1368302
X16500Y1369946
X24500Y1370118
X20000Y1371399
Y1374599
X16500Y1375946
X24500Y1375884
X27529Y1377700
Y1380900
X16500Y1382544
X24500Y1382716
X20000Y1383998
Y1387198
X16500Y1388544
X24500Y1388483
X27529Y1390299
Y1393499
X16500Y1395142
X24500Y1395315
X20000Y1396596
Y1399796
X16500Y1401142
X24500Y1401081
X27529Y1402897
Y1406097
X16500Y1407741
X24500Y1407913
X20000Y1409195
Y1412395
X16500Y1413741
X27000Y1417500
X32500Y1417600
X21000Y1424500
X37000Y1443500
X28000Y1444000
X30500Y1463500
X22000Y1487000
X16500Y1512500
X36201Y1518123
X33001
X16500Y1521031
X36401Y1521623
X32801
X24500Y1522401
X27529Y1524156
Y1527356
X16500Y1529000
X24500Y1529111
X20000Y1530454
Y1533654
X16500Y1535000
X24500
X27529Y1536755
Y1539955
X16500Y1541500
X24500Y1541710
X20000Y1543052
Y1546252
X24500Y1547598
X16500Y1548000
X27529Y1549353
Y1552553
X16500Y1554000
X24500Y1554308
X20000Y1555650
Y1558850
X24500Y1560197
X16500Y1560500
X27529Y1561952
Y1565152
X16500Y1566500
X24500Y1566907
X20000Y1568249
Y1571449
X16500Y1573000
X24500Y1582244
X16500Y1582500
X27529Y1583999
Y1587199
X16500Y1588500
X24500Y1588954
X20000Y1590296
Y1593496
X24500Y1594842
X16500Y1595000
X27529Y1596597
Y1599797
X16500Y1601500
X24500Y1601552
X20000Y1602894
Y1606094
X24500Y1607441
X16500Y1607500
X27529Y1609196
Y1612396
X16500Y1614000
X24500Y1614151
X20000Y1615493
Y1618693
X16500Y1620000
X24500Y1620039
X27529Y1621794
Y1624994
X16500Y1626500
X24500Y1626749
X20000Y1628091
Y1631291
X24500Y1632638
X16500Y1633000
X27529Y1634393
Y1637593
X24500Y1639348
X16500Y1639845
X20000Y1640690
Y1643890
X16500Y1644735
Y1665044
X20000Y1665887
Y1669087
X16500Y1669933
X24500Y1670624
X27529Y1672379
Y1675579
X16500Y1677000
X24500Y1677334
X20000Y1678485
Y1681685
X24500Y1683222
X16500Y1683170
X27529Y1684977
Y1688177
X16500Y1689500
X24500Y1689932
X20000Y1691083
Y1694283
X24500Y1695821
X16500Y1696000
X27529Y1697576
Y1700776
X16500Y1702500
X24500Y1702531
X35900Y1706000
X34224Y1709000
X16500Y1712000
X20000Y1713131
X38000Y1715000
X20000Y1716331
X16500Y1717462
X24500Y1717868
X27529Y1719623
Y1722823
X16500Y1724000
X24500Y1724578
X20000Y1725729
Y1728929
X24500Y1730466
X16500Y1730658
X27529Y1732221
Y1735421
X16500Y1736500
X24500Y1737176
X20000Y1738328
Y1741528
X24500Y1743065
X16500Y1743356
X27529Y1744820
Y1748020
X16500Y1749000
X24500Y1749775
X20000Y1750926
Y1754126
X24500Y1755663
X16500Y1756052
X27529Y1757418
Y1760618
X24500Y1762373
X16500Y1765000
X22219Y1768323
X31981
X28700Y1769558
X25500
X16500Y1774500
Y1784000
Y1790500
X39400Y1819900
X39500Y1823300
X38400Y1846750
X38300Y1859050
X38500Y1871350
X5500Y1880685
X38200Y1883800
X5500Y1888685
X19974Y1943969
X5500Y1953685
X20000Y1960000
X33700Y1960300
X30200Y1970300
X5500Y1973685
X20000Y1980000
X12559Y1986626
X32559
X72559
X52559
X40000Y1980000
X57800Y1961800
X71666Y1961325
X76900Y1957900
X73400
X43935Y1957215
X73400Y1954400
X76900
X56875Y1954250
X40000Y1940000
X60000Y1928000
Y1920000
X40556Y1917072
X44000Y1900000
X74300
X60000
X46868Y1887765
X52000Y1887500
X60897Y1885848
X41700Y1883700
X52000Y1877500
X48000
X42100Y1871350
X76975Y1864000
X42200Y1859050
X67800Y1855200
X45200Y1854700
X45100Y1850800
X42300Y1846750
X45200Y1843300
X72123Y1841183
X45200Y1839300
X40800Y1832300
Y1827300
X77159Y1818277
X74100Y1796200
X72500Y1788209
Y1773209
Y1758209
X67500Y1757886
X68000Y1753607
Y1750407
X71000Y1747284
X67500Y1746128
X71015Y1738000
X67000
X72500Y1713209
Y1708209
X66400Y1706900
X66500Y1694000
X72500Y1683209
X71000Y1680000
X51635Y1665355
X68000Y1651500
X40500Y1608500
X64525Y1591016
X42919Y1583175
X64500Y1581500
X72000Y1551500
X72100Y1536400
X47368Y1527323
X43000Y1526000
X42644Y1521957
X46893Y1519979
X42960Y1517408
X46845Y1514264
X72100Y1509900
X48000Y1505500
Y1482000
X69365Y1474719
X76750Y1462762
X73000Y1455100
X62962Y1422600
X70838Y1384165
X72285Y1365633
X72500Y1352697
X67500Y1352366
X68000Y1348095
Y1344895
X71000Y1341772
X67500Y1340624
X71000Y1335488
X64000Y1328500
X58500Y1320500
X58900Y1317000
X72500Y1307697
Y1302697
Y1277697
X71000Y1274500
X67500Y1191500
X75000Y1182500
X41500Y1178000
Y1165500
X40097Y1142513
X39959Y1128308
X41608Y1125065
X71000Y1109000
X42286Y1089500
Y1085500
X67090Y1070360
X41000Y1057500
X77750Y1056750
X74000Y1047500
X64037Y1016654
X72500Y977185
Y962185
X67000Y953500
X72500Y947185
X67500Y946855
X68000Y942583
Y939383
X71000Y936260
X67500Y935111
X65500Y927500
X71000Y925500
X51000Y913500
X72500Y902185
X47500Y901500
X63500Y899000
X72500Y897185
Y872185
X71000Y869000
X65500Y867500
X67500Y822500
X63100Y788800
X73500Y779500
X49500Y771000
X51500Y757500
X61500Y748000
X62000Y736500
X51500Y730500
X76000Y706500
X61500Y682500
X76500Y665000
X59000Y659500
X46500Y653500
X50560
X48000Y649500
X70500Y648500
X49000Y638000
X62426Y607740
X72900Y605400
X61100Y600100
X61900Y584300
X72500Y571673
Y556673
Y541673
X67500Y541342
X68000Y537071
Y533871
X71000Y530748
X67500Y529600
X71000Y524464
X72500Y496673
Y491673
X51500Y469000
X72500Y466673
X71000Y463500
X48822Y393916
X52066Y370649
X46487Y360400
X66610Y295956
X56024Y292549
X66512Y287899
X67000Y269000
X77306Y259381
X70500Y242988
X40000Y240000
Y220000
X60306Y212338
X40000Y200000
Y180000
X72500Y166161
X40000Y160000
X72500Y151161
X40000Y140000
X72500Y136161
X67500Y135830
X68000Y131559
Y128359
X71000Y125236
X67500Y124088
X40000Y120000
Y100000
X72500Y91161
Y86161
X60000Y80000
X40000
X72500Y61161
X40000Y60000
X71000Y58000
X40000Y40000
Y20000
X50018Y5500
X70018
X90018
X110018
X116600Y46800
X96100Y52300
X99500Y53844
Y58244
X96000Y60868
X109038Y62310
X105000Y63793
Y66993
X109038Y68476
X96000Y70118
X99500Y72642
Y77042
X96000Y79567
X109000Y81106
X105000Y82691
Y85891
X109000Y87476
X96000Y89015
X99500Y91540
Y95940
X96000Y98464
X109160Y100476
X105000Y101588
Y104788
X109160Y105900
X96000Y107913
Y114212
Y119000
Y123661
X104000Y125000
X96000Y134000
X114579Y137775
X96000Y139409
X99500Y141933
Y146333
X96000Y148858
X108917Y150188
X105000Y151982
Y155182
X108917Y156976
X96000Y158307
X100000Y180000
X99800Y194200
X80000Y200000
X99300Y201000
X100400Y208300
X97400Y220200
X80153Y230246
X80300Y234465
X85427Y239715
X85250Y247238
X111500Y276000
X97000Y296500
X84500Y315000
X114295Y338300
X92700Y358400
X95849Y361564
X113500Y362500
X106500
X110000
X117000
Y366000
X110000
X106500
X113500
X97400Y366600
X119159Y405100
X96900Y406000
X104400
X100400
X107900
X112600Y439000
Y442500
X98300Y443400
X96000Y456732
X99500Y459256
Y463656
X96000Y466181
X109044Y467822
X105000Y469305
Y472505
X109044Y473988
X96000Y475630
X99500Y478154
Y482554
X96000Y485079
X109000Y486618
X105000Y488203
Y491403
X109000Y492988
X96000Y494527
X99500Y497052
Y501452
X96000Y503976
X109138Y505912
X105000Y507100
Y510300
X109138Y511488
X96000Y513425
Y519724
Y524000
Y529173
X104000Y531000
X96000Y539500
Y544921
X99500Y547445
Y551845
X96000Y554369
X108917Y555700
X105000Y557494
Y560694
X108917Y562488
X96000Y563819
X99900Y582400
X94700Y599800
X80000Y600000
X89400Y603250
X95900Y605500
X88600Y623300
X80153Y635758
X80300Y639977
X85223Y645227
X85250Y652750
X102500Y737500
X117945Y743800
X106500Y768000
X117000
X110000
X113500
X87075Y768250
X83200Y768300
X110000Y771500
X113500
X106500
X117000
X97000Y772100
X86900Y774750
X80215Y777137
X119534Y810975
X104600Y811300
X100600
X108100
X97100
X116000Y814500
X112500Y845200
Y848700
X98300Y850400
X96000Y862244
X99500Y864768
Y869168
X96000Y871692
X109040Y873334
X105000Y874817
Y878017
X109040Y879500
X96000Y881142
X99500Y883666
Y888066
X96000Y890591
X109000Y892130
X105000Y893715
Y896915
X109000Y898500
X96000Y900039
X99500Y902564
Y906964
X96000Y909488
X109187Y911424
X105000Y912612
Y915812
X109187Y917000
X96000Y918937
Y925236
Y930000
Y934685
X104000Y936000
X96000Y945000
Y950433
X99500Y952957
Y957357
X96000Y959882
X109000Y961212
X105000Y963006
Y966206
X109000Y968000
X96000Y969331
X96532Y977682
X107400Y994000
X99600Y1001400
X93000Y1005700
X96500Y1011200
X106100Y1030000
X81689Y1039600
X103200Y1042500
X81689Y1049400
X102403Y1058209
X83248Y1059636
X111500Y1145000
X117900Y1149200
X87900Y1173300
X113500Y1173500
X117000
X106500
X110000
X96100Y1176700
X106500Y1177000
X117000
X110000
X113500
X88500Y1177300
X85300Y1182000
X81500Y1213000
X119534Y1216475
X108000Y1217000
X104500
X95700Y1219700
X99100Y1219800
X112600Y1250800
X118250Y1252050
X112600Y1254300
X98300Y1255900
X96000Y1267756
X99500Y1270280
Y1274680
X96000Y1277205
X109040Y1278846
X105000Y1280329
Y1283529
X109040Y1285012
X96000Y1286654
X99500Y1289178
Y1293578
X96000Y1296103
X109000Y1297642
X105000Y1299227
Y1302427
X109000Y1304012
X96000Y1305551
X99500Y1308076
Y1312476
X96000Y1315000
X109133Y1316936
X105000Y1318124
Y1321324
X109133Y1322512
X96000Y1324449
Y1330748
Y1335000
Y1340197
X104000Y1341000
X96000Y1350500
Y1355945
X99500Y1358469
Y1362869
X96000Y1365393
X109000Y1366724
X105000Y1368518
Y1371718
X109000Y1373512
X96000Y1374843
X117690Y1397168
X96250Y1414400
X99900Y1419600
X100000Y1423000
X99300Y1431200
X80153Y1446781
X80300Y1451000
X82748Y1455148
Y1465560
X110000Y1470000
X118000
X114000
X80000Y1480000
X109500Y1486000
X116500Y1505500
X90500Y1521500
X82005Y1540500
X85808
X109050Y1540600
X96000Y1541100
X105700Y1548200
X91125Y1565900
X80465Y1570120
X103500Y1573200
X107000
X110500
X114000
X88076Y1575924
X107000Y1576700
X103500
X114000
X110500
X113841Y1580900
X119534Y1621975
X104500Y1622500
X100500
X97000
X108000
X117000Y1654600
X113200Y1656300
Y1659800
X98600
X96000Y1673268
X99500Y1675792
Y1680192
X96000Y1682716
X109040Y1684358
X105000Y1685841
Y1689041
X109040Y1690524
X96000Y1692166
X99500Y1694690
X117300Y1696500
X99500Y1699090
X96000Y1701615
X109000Y1703154
X105000Y1704739
Y1707939
X109000Y1709524
X96000Y1711063
X99500Y1713588
Y1717988
X96000Y1720512
X109137Y1722448
X105000Y1723636
Y1726836
X109137Y1728024
X96000Y1729961
Y1736260
Y1745109
X104000Y1747800
X96000Y1755158
X100000Y1759000
X96000Y1761457
X99500Y1763981
Y1768381
X96000Y1770906
X109030Y1772524
X105000Y1774030
Y1777230
X109030Y1778736
X100000Y1780000
X96000Y1780355
X93625Y1802200
X85000Y1817100
X100300Y1820800
X100287Y1825915
X100300Y1830000
X91036Y1835282
X93600Y1848200
X98000Y1848800
X80600Y1848900
X113500Y1875970
X111000Y1879570
X115228Y1879770
X112366Y1883985
X100100Y1896300
X107543Y1898024
X80000Y1920000
X100000Y1928000
X80000
X87500Y1954300
X80400Y1954400
X83900
X80400Y1957900
X118500Y1971400
X107000Y1974100
X110700
X98800
X94700
X114200
X103300
X80000Y1980000
X100300Y1980900
X112559Y1986626
X92559
X152559
X132559
X139100Y1977100
X133000
X150600Y1970300
X137300Y1969900
X136800Y1959900
X150800Y1958900
X123200Y1947250
X130500Y1946200
X148095Y1940906
X144595Y1938382
Y1933982
X148095Y1931457
X134995Y1929650
X139095Y1928333
Y1925133
X134995Y1923650
X148095Y1922008
X128800Y1921300
X144595Y1919484
Y1915084
X148095Y1912559
X134895Y1910650
X139095Y1909435
Y1906235
X134895Y1905020
X148095Y1903111
X144595Y1900586
X128200Y1900300
X144595Y1896186
X148095Y1893662
X134895Y1891650
X139095Y1890538
Y1887338
X134895Y1886150
X148095Y1884213
X129500Y1883500
X148095Y1877914
X140000Y1870000
X148095Y1868465
X148000Y1864000
X148095Y1859016
X128800Y1854000
X148095Y1852717
X144595Y1850193
Y1845793
X148095Y1843268
X135065Y1841650
X139095Y1840144
Y1836944
X135065Y1835438
X148095Y1833819
X140000Y1820000
X136500Y1811500
X151452Y1810000
X145500Y1807500
X148000Y1787000
X157898Y1780145
X125000Y1757834
Y1753534
Y1750334
Y1746034
X136500Y1733000
X159800Y1730000
X140825Y1729825
X137000Y1727500
X147200Y1724400
X140300Y1724100
X144400Y1720400
X136700Y1720100
X123000Y1702000
X136600Y1681900
X120000Y1678000
X137000Y1666500
X143000Y1656000
X121700Y1654800
X126900Y1654700
X153700Y1633600
X133800Y1630100
X130300
X137300
X126800
X150200Y1628000
X133800Y1626600
X137300
X126800
X130300
X143500Y1625500
X143300Y1586900
X146800
X135300Y1585100
X138800
X130600Y1549100
X147700Y1545500
X144200
X148095Y1535394
X144595Y1532870
Y1528470
X148095Y1525945
X134995Y1524138
X139095Y1522821
X123400Y1522600
X139095Y1519621
X134995Y1518304
X148095Y1516496
X144595Y1513972
Y1509572
X148095Y1507047
X128250Y1506500
X135095Y1505508
X123500Y1505200
X139095Y1503923
Y1500723
X135095Y1499138
X148095Y1497599
X144595Y1495074
Y1490674
X148095Y1488150
X134935Y1486138
X139095Y1485026
Y1481826
X134935Y1480714
X148095Y1478701
Y1472402
X122000Y1470000
X130000
X148095Y1468752
X126000Y1466000
X140000Y1464000
X148095Y1462953
X148000Y1458000
X148095Y1453504
X126916Y1447364
X148095Y1447205
X144595Y1444681
Y1440281
X148095Y1437756
X135095Y1436426
X139095Y1434632
Y1431432
X135095Y1429638
X148095Y1428307
X121320Y1425396
X143087Y1403623
X140125Y1381300
X151125Y1376608
X158875Y1376100
X129500Y1352321
Y1348021
X147956Y1347802
X129500Y1344821
X154709Y1344513
X129500Y1340521
X140000Y1340000
Y1300000
X120000Y1280000
X140000
X129150Y1252050
X127000Y1224000
X134000
X130500
X137500
X157325Y1223850
X134000Y1220500
X127000
X137500
X130500
X120000Y1220000
X146700Y1219600
X158052Y1216052
X124100Y1181025
X143500Y1180400
X136000
X147000
X139500
X122400Y1149200
X131500Y1146700
Y1143200
X147800Y1140000
X148095Y1129882
X144595Y1127358
X123500Y1123500
X144595Y1122958
X148095Y1120433
X135001Y1118626
X139095Y1117309
Y1114109
X135001Y1112792
X148095Y1110984
X144595Y1108460
X122500Y1107000
X144595Y1104060
X148095Y1101535
X135095Y1099996
X139095Y1098411
Y1095211
X135095Y1093626
X148095Y1092087
X144595Y1089562
Y1085162
X129500Y1084500
X148095Y1082638
X134941Y1080626
X139095Y1079514
Y1076314
X134941Y1075202
X148095Y1073189
X139300Y1067000
X148095Y1066890
X140000Y1059500
X148095Y1057441
X148000Y1053500
X129000Y1051500
X148095Y1047992
Y1041693
X144595Y1039169
Y1034769
X148095Y1032244
X135095Y1030914
X139095Y1029120
Y1025920
X135095Y1024126
X148095Y1022795
X137500Y1014500
X157000Y957500
X155900Y954200
X157200Y950800
X140000Y900000
X126800Y842500
X122251Y842400
X148600Y818700
X130500Y818500
X134000
X137500
X127000
X156800Y816000
X134000Y815000
X127000
X130500
X137500
X147100Y814200
X143800Y807400
X136100Y775600
X143600
X139600
X147100
X124966Y775525
X122445Y743800
X131400Y741700
Y738200
X145800Y737100
X148095Y724370
X144595Y721846
X125500Y719000
X144595Y717446
X148095Y714921
X134993Y713114
X139095Y711797
Y708597
X134993Y707280
X148095Y705472
X144595Y702948
Y698548
X148095Y696023
X135095Y694484
X139095Y692899
Y689699
X135095Y688114
X148095Y686575
X144595Y684050
Y679650
X148095Y677126
X134941Y675114
X139095Y674002
Y670802
X134941Y669690
X148095Y667677
Y661378
X140000Y654000
X148095Y651929
X148000Y648000
X148095Y642480
Y636181
X144595Y633657
Y629257
X148095Y626732
X135095Y625402
X139095Y623608
Y620408
X135095Y618614
X148095Y617283
X131500Y610500
X139500Y600400
X159600Y581400
X150850Y574350
X155500Y574000
X158500Y569500
X132350Y563750
X157500Y551200
X157750Y544750
X124000Y541373
X157750Y541250
X124000Y537073
Y533873
Y529573
X140000Y480000
Y460000
X120000
X140000Y440000
X120800Y438000
X125300
X148700Y413400
X134000Y413000
X130500
X127000
X137500
X157200Y412000
X137500Y409500
X134000
X127000
X130500
X145900Y408500
X158500Y408000
X136000Y370000
X147000
X139500
X124466Y370025
X143500Y370000
X126445Y338300
X131300Y335900
Y332400
X145800
X148095Y318858
X144595Y316334
X125000Y312000
X144595Y311934
X148095Y309409
X134995Y307602
X139095Y306285
Y303085
X134995Y301768
X148095Y299960
X144595Y297436
X126000Y293000
X144595Y293036
X148095Y290511
X135095Y288972
X139095Y287387
Y284187
X135095Y282602
X148095Y281063
X144595Y278538
Y274138
X148095Y271614
X134941Y269602
X139095Y268490
X125500Y265500
X139095Y265290
X134941Y264178
X148095Y262165
Y255866
X129000Y255500
X143600Y252100
X128500Y248000
X140000Y247500
X148095Y246417
X148000Y241500
X148095Y236968
X132500Y236000
X148095Y230669
X144595Y228145
Y223745
X148095Y221220
X135064Y219602
X139095Y218096
Y214896
X135064Y213390
X148095Y211771
X135500Y200500
X159500Y181000
X154875Y160500
X147125
X150557Y142854
X124000Y135859
X158300Y135200
X124000Y131559
Y128359
Y124059
X140000Y80000
X154700Y65000
X150200
X138200Y64900
X141700
X128200Y61300
X131700
X121600Y54700
X125700Y54400
X152400Y41500
X155018Y5500
X170018
X190018
X170034Y31475
X177300Y35500
X180800
X187800
X184300
X196665Y35585
X184300Y39000
X177300
X180800
X187800
X180000Y80000
X160000
X184461Y103368
X179147Y137913
X167298Y147703
Y151203
X198800Y158000
Y162500
Y167000
X180000Y180000
X171595Y203917
Y218917
X176492Y231103
X180100Y231095
X171595Y233917
X180000Y235394
X176800
X194500Y236902
X190500Y238501
Y241701
X194500Y243300
X173095Y244842
X172900Y249400
X171595Y278917
Y283917
Y308917
X173000Y312500
X173800Y379800
X163500Y423000
X160000Y440000
X180000Y460000
X170500Y478500
X180000Y480000
X160000Y520000
X180000
X188854Y527099
Y530902
X195500Y531250
X165138Y536500
X195500Y538750
Y546250
X174000Y553500
X184500
X195250Y561300
Y576700
X180000Y580000
Y600000
X171595Y609429
X180000Y620000
X171595Y624429
X176492Y636617
X180308
X171895Y639429
X190500Y639713
X176800Y640906
X180000
X190500Y644013
Y647213
X173095Y650354
X190500Y651513
X173000Y655200
X171595Y684429
Y689429
Y714429
X173000Y718000
X180000Y720000
X160000Y880000
X190330Y913530
X167000Y935909
Y939309
Y942509
Y945909
X161200Y946100
X182000Y949000
X195500Y949750
X161700Y950800
X174500Y960000
X178000
X198900Y965477
Y969500
Y974000
Y978500
X180000Y980000
X161095Y980622
X194200Y985900
X162200Y988000
X180000Y1000000
X171595Y1014941
Y1029941
X176492Y1042129
X180308
X171595Y1044941
X190600Y1045226
X180000Y1046418
X176800
X190500Y1049525
Y1052725
X173095Y1055866
X190600Y1057024
X173000Y1060400
X196000Y1070300
X180000Y1080000
X171595Y1089941
Y1094941
X180000Y1100000
X171595Y1119941
X180000Y1120000
X173000Y1123500
X180000Y1140000
Y1220000
Y1280000
X160000
X180000Y1300000
X160000
Y1340000
X180000
X179147Y1353048
X160000Y1360000
X167301Y1363238
Y1366838
X193400Y1373000
Y1377500
Y1382000
X180000Y1400000
Y1420000
X171595Y1420453
Y1435453
X180000Y1440000
X180308Y1447634
X176492
X171895Y1450453
X190400Y1450738
X176800Y1451930
X180000
X190500Y1455037
Y1458237
X173095Y1461378
X190400Y1462536
X173100Y1466300
X171595Y1495453
X180000Y1500000
X171595Y1500453
X180000Y1520000
X171595Y1525453
X173000Y1529000
X189300Y1577200
X172000Y1595000
X171500Y1613500
X182500Y1622500
X181500Y1641500
X180000Y1680000
X160000Y1700000
X180000
X160200Y1710300
X160000Y1720000
X191353Y1772940
X177717Y1778162
X197900Y1781500
Y1786000
Y1790500
X180075Y1790692
X160000Y1800000
X180000
X171595Y1825965
X180000Y1840000
X171595Y1840965
X180308Y1853146
X176492
X171595Y1855965
X180000Y1857442
X176800
X194620Y1859298
X190500Y1860549
Y1863749
X194620Y1865000
X173095Y1866890
X173500Y1871700
X180000Y1880000
Y1900000
X171595Y1900965
Y1905965
Y1930965
X173000Y1934500
X180000Y1940000
X192559Y1986626
X172559
X212559
X232559
X220000Y1980000
X200000
Y1960000
X220000
X200000Y1940000
X220000
Y1920000
X200000
Y1900000
X220000
X200000Y1880000
X220000Y1840000
Y1800000
X200000
X207600Y1777500
X222500Y1776200
X224875Y1768100
X220800Y1763750
X203299Y1763350
Y1759750
X220200Y1740900
X206000Y1735000
X220000Y1734500
Y1720000
Y1680000
X200000
Y1660000
X220000
X203500Y1618500
X229500Y1614500
X220000Y1580000
Y1560000
X200000
X202000Y1534000
X200000Y1520000
X220000
X200000Y1500000
Y1480000
Y1460000
X214500Y1459000
X200000Y1440000
X215000Y1368000
X227000Y1359500
X220000Y1340000
X200000
Y1300000
X220000
X200000Y1280000
X220000
Y1220000
X200000Y1200000
X208500Y1190000
X200000Y1160000
X220000Y1140000
X200000
X220000Y1120000
X200000
X220000Y1100000
X200000
X220000Y1080000
X200000
X220000Y1060000
Y1040000
Y1020000
X207350Y968627
X201125Y957200
X208875
X229500Y946600
X220000Y940000
X200000Y900000
X220000Y880000
Y860000
X214700Y784200
X200000Y760000
X220000Y740000
X200000
Y720000
X220000
Y700000
X200000
Y680000
X220000
Y660000
X200000
X220000Y640000
Y620000
X200000Y580000
X200250Y572100
X206500Y546250
Y538750
Y531250
X200000Y520000
X220000
Y480000
X200000
Y460000
X220000
X200000Y440000
X220000Y420000
X200000
X220000Y360000
X200000
Y340000
X220000
Y320000
X200000
Y300000
X220000
X200000Y280000
X220000
X200000Y260000
X220000
Y220000
X200000Y200000
X220000
X200000Y180000
X220000
Y160000
Y140000
Y80000
X200000
X220500Y67500
X205625Y38750
X208150Y32250
X230018Y5500
X210018
X250018
X270018
X240000Y20000
X260000
X240000Y40000
X260000
X240000Y80000
X260000
Y100000
X240000Y140000
Y160000
X260000
Y180000
X240000
Y200000
X260000
X240000Y220000
X260000
X240000Y260000
Y280000
X260000Y300000
X240000
X260000Y320000
X240000
Y340000
X260000
X240000Y360000
X260000
Y420000
Y440000
Y460000
Y480000
Y520000
Y560000
X273500Y565000
X270000Y567130
Y570933
X273500Y573000
Y577000
X270000Y579030
X240000Y580000
X270000Y582833
X273500Y585000
Y589000
X269800Y590930
Y594733
X273500Y597000
X260000Y600000
X240000
X260000Y620000
Y640000
Y700000
Y720000
X240000Y760000
X260000Y860000
X240000
Y880000
X260000
Y940000
X240000
X260000Y980000
X240000Y1000000
X260000Y1020000
X240000
Y1040000
X260000
X240000Y1060000
X260000
X240000Y1080000
X255674Y1099470
X240000Y1100000
Y1120000
X260000
Y1160000
X240000Y1180000
X260000Y1200000
X240000
X260000Y1220000
X240000
X260000Y1260000
Y1280000
X240000
X260000Y1300000
X240000
X260000Y1340000
X240000
Y1367500
Y1400000
X260000
X273500Y1403500
Y1407500
Y1411500
X270000Y1413530
Y1417333
X273500Y1419500
X260000Y1420000
X240000
X273500Y1423500
X270100Y1425697
Y1429500
X273500Y1431500
X240000Y1440000
X260000
X279650Y1448000
X240000Y1460000
Y1480000
Y1500000
X258585Y1508386
X260000Y1520000
X240000
Y1560000
X260000
Y1600000
Y1620000
Y1660000
X240000
X260000Y1680000
X240000
X259000Y1702500
X242500
X248500Y1713005
Y1716808
X251800Y1718400
X265500Y1722000
X276402Y1726146
X272599
X255495Y1738573
X251692
X260000Y1740000
X256000Y1745500
X251900Y1769900
X268800Y1774600
X279500Y1795000
X271500
X260000Y1800000
X240000
Y1840000
X260000
X256500Y1880000
X240000
X256549Y1898366
X240000Y1920000
Y1940000
X260000
X240000Y1960000
X260000
Y1980000
X240000
X252559Y1986626
X272559
X292559
X312559
X280000Y1980000
X300000
Y1960000
X280000
X300000Y1940000
X280000
X280071Y1924667
X300000Y1920000
Y1900000
Y1880000
Y1860000
Y1840000
X280000
X300000Y1800000
X287500Y1795000
X297000Y1777000
Y1752000
X302000
X293000Y1742500
X288000
X284000Y1731250
X313200Y1727300
X317000
X301800Y1722100
X283500Y1722000
X305300Y1715700
X315000Y1712000
X306200Y1709600
X289300Y1701800
X285000Y1700600
Y1697400
X289300Y1696200
X292400Y1693400
X295600
X313500Y1692500
X318156Y1692440
X306200Y1689400
X295800Y1688900
X292200
X300000Y1620000
X280000
X300000Y1600000
X280000
X300000Y1560000
X280000
X300000Y1520000
X280000
X293830Y1451500
X297633
X282030Y1451400
X285833
X309633Y1451300
X305830
X311600Y1448000
X291600
X287600
X303600
X299600
X300984Y1433500
X297500Y1424000
X302500
X300000Y1421500
X302500Y1419000
X297500
X301400Y1401500
X297600Y1392000
X319500Y1389000
X315500
X303500
X307500
X311500
X284900Y1383500
X293100
X290970Y1380000
X280000
X287167
X280000Y1340000
X300000Y1300000
X280000
Y1280000
X300000
Y1260000
X280000
X294500Y1254000
X295000Y1245000
X300000Y1240000
X313200Y1228800
X317000
X302500Y1224000
X280000Y1220000
X304500Y1217500
X314437Y1213382
X305200Y1208300
X280000Y1200000
X312500Y1194000
X313500Y1187500
X296011Y1185470
X280000Y1180000
X295400Y1172655
X309000Y1166500
X300000Y1120000
X280000
X294000Y1111500
X300000Y1100000
Y1080000
Y1060000
X280000Y1040000
X300000
X280000Y1020000
X300000
Y1000000
X280000
Y980000
X300000
X292500Y965500
X280000Y940000
X300000
X305200Y913000
X295200
Y903000
X305200
X280000Y880000
X300000
X280000Y860000
X317000Y857900
X313200
X303500Y853100
X304400Y846700
X315000Y842000
X292000Y837000
X304500Y836700
X312000Y824500
X301300Y822550
X280000Y820000
X297840Y804552
X309000Y795000
X313500Y792000
X293500Y738000
X298200Y720000
X298500Y680200
Y660200
X280000Y640000
X300000
X301833Y621000
X298030
X280000Y620000
X286130Y615700
X289933
X310030Y615500
X313833
X284000Y612000
X316000
X308000
X292000
X296000
X304000
X297500Y588000
X302500
X288000Y586484
X300000Y585500
X297500Y583000
X302500
X317500Y559000
X290580
X313000
X298450
X296470Y555500
X292667
X297300Y505017
X300000Y480000
X280000
X300000Y460000
X280000
Y440000
X300000
X317000Y427500
X313200
X303200Y422600
X280000Y420000
X304400Y416200
X315000Y412000
X294500Y408000
X305100Y407700
X312500Y393050
X318656Y391440
X313500Y386000
X293000Y385000
X304553Y374081
X309000Y365000
X313500Y362000
X280000Y360000
Y340000
X300000
X280000Y320000
X300000
Y280000
X280000Y220000
X300000
X280000Y200000
X300000
X280000Y180000
X292600Y166955
X300000Y140000
X280000Y120000
X300000
Y100000
X280000
X300000Y80000
X280000
X300000Y60000
X280000Y40000
X300000
Y20000
X280000
X290018Y5500
X310018
X350018
X330018
X320000Y20000
X340000
X320000Y40000
X340000
Y60000
X320000
X358000Y64000
X352500Y68500
X344500Y71750
X320000Y80000
X340000
X358500Y93500
X340000Y100000
X320000
X340000Y120000
X320000
X357250Y124000
X320000Y140000
X340000
X320000Y160000
X340000
Y180000
X320000Y220000
X340000Y240000
X320000
X340000Y260000
X320000Y280000
Y320000
Y340000
X348256Y344114
X356257Y344176
X349870Y348870
X356250Y349000
X349706Y355693
X320000Y359500
X327500Y373000
Y377000
X359000Y389000
X331500
X326156Y391440
X331500Y393000
X359000Y394500
Y400000
X321400Y404400
X359000Y405500
X337500Y406250
X331300Y408500
X321500
X359000Y411000
X321500Y413000
X339500Y416750
X321500Y417000
Y421000
Y425200
X350241Y444377
X343750Y451000
X350137Y451250
X343729Y455810
X351729
X320000Y460000
X340000Y540000
X320000
X340000Y560000
X336000Y570580
X339500Y572667
Y576470
X336000Y578600
X329600Y583200
X320100Y587200
X332500Y589000
Y593000
Y597000
X340000Y600000
X332500Y601000
Y605000
X340000Y620000
X320000Y640000
X340000Y660000
Y680000
X320000Y700000
X340000
Y720000
X320000
X340000Y740000
Y780000
X325053Y782652
X320000Y789500
X358000Y794000
X327500Y803000
X358800Y803600
X327500Y807000
X321500
X326167Y811099
Y814902
X359000Y819000
X331500
X323000Y819500
X331500Y823000
X359000Y824500
Y830000
X321400Y834400
X359000Y835500
X337500Y836250
X321500Y838500
X331300
X359000Y841000
X321500Y843000
X339500Y846750
X321500Y847000
Y851000
Y855200
X343749Y874298
X343894Y880707
X351740Y880717
X351792Y885835
X343770Y885897
X355622Y919857
X335823Y940330
X340000Y960000
Y980000
X320000Y1000000
X340000
X320000Y1020000
X340000
X320000Y1040000
X340000
Y1060000
X320000
X340000Y1080000
X320000
Y1100000
X340000
X320000Y1140000
X340000
Y1160000
X320000Y1161000
X354228Y1164233
X327500Y1174500
Y1178500
X359175Y1179640
X359000Y1190500
X331500
Y1194500
X359000Y1196000
Y1201500
X321400Y1205900
X359000Y1207000
X337500Y1207750
X331300Y1210000
X321500
X359000Y1212500
X321500Y1214500
X339500Y1218250
X321500Y1218500
Y1222500
X321600Y1226600
X343749Y1245719
X351771Y1252213
X343822Y1252222
X351750Y1257380
X343760Y1257381
X320000Y1260000
Y1280000
X340000Y1340000
Y1360000
X327500Y1368500
X328000Y1374000
X340000Y1380000
X328000Y1381500
X326500Y1405400
X330300Y1407297
Y1411100
X326500Y1413500
Y1417500
X330000Y1419667
Y1423470
X326500Y1425700
Y1429700
X330000Y1431367
Y1435170
X326500Y1437700
X340000Y1460000
Y1480000
X320000Y1540000
Y1560000
Y1600000
X356247Y1644123
X348257Y1644132
X348250Y1649000
X356174Y1649291
X334500Y1650000
X356238Y1655722
X334500Y1665000
X327500Y1673000
Y1677000
X359000Y1689000
X331500Y1691000
X325656Y1692440
X359000Y1694500
X331500Y1695000
X359000Y1700000
X321400Y1704400
X359000Y1705500
X337500Y1706250
X321500Y1708500
X331500
X359000Y1711000
X321500Y1713000
X339500Y1716750
X321500Y1717000
Y1721000
Y1725200
X343709Y1744187
X343668Y1750741
X351750Y1751000
X343750Y1755500
X351750
X320000Y1760000
Y1780000
X340000Y1800000
X320000Y1820000
X340000
Y1840000
X320000
X340000Y1860000
X320000
Y1880000
X340000
X320000Y1900000
X340000
X320000Y1920000
X340000
Y1940000
X320000
Y1960000
X340000
Y1980000
X320000
X352559Y1986626
X332559
X372559
X392559
X360000Y1980000
X380000
Y1960000
X360000
X380000Y1940000
X360000
Y1920000
X380000
Y1900000
X360000
X380000Y1880000
X360000
Y1860000
X380000
Y1840000
X360000
Y1820000
X380000
X360000Y1800000
X380000
X368500Y1768000
X376808Y1755434
X373005
X383000Y1736300
X379000Y1736000
X369000Y1734500
X372500
X365400Y1734400
X383000Y1728700
X375700Y1727750
X365700Y1727700
X379000Y1726000
X393000Y1723500
X375500Y1711000
X364500
X370000
X381000
Y1705500
X375500
X370000
X364500
X381000Y1700000
X370000
X375500
X364500
X381000Y1694500
X365000
X375500
X370000
X395500Y1690500
X381000Y1689000
X375500
X365000
X370000
X376890Y1678000
X369100Y1673700
X388750Y1673000
X385250
X376000Y1667000
X372500
X368500Y1664000
X380000Y1660000
Y1580000
X360000Y1560000
X380000Y1540000
X360000
X380000Y1520000
X360000
X380000Y1500000
X360000
X380000Y1440000
Y1420000
Y1400000
Y1380000
X360000
Y1360000
X380000
X360000Y1340000
X380000
X360000Y1320000
X380000
Y1300000
X379270Y1257380
X387292Y1257360
X379395Y1252274
X387208Y1252212
X379249Y1245782
X370200Y1239700
X368500Y1236500
X372000
X365200Y1229800
X375200Y1229750
X391500Y1218500
X381000Y1212500
X375500
X370000
X364500
X381000Y1207000
X364500
X370000
X375500
X381000Y1201500
X364500
X375500
X370000
X375500Y1196000
X381000
X365000
X370000
X365000Y1190500
X381000
X370000
X375500
X398750Y1188250
X396750Y1181250
X364300Y1174900
X374200Y1174750
X371000Y1168000
X367500
X363500Y1165000
X391765Y1157852
X383750Y1150500
X391900Y1150250
X383757Y1145655
X391758Y1145676
X360000Y1140000
Y1100000
X380000
Y1080000
X360000
X380000Y1060000
X360000
X380000Y1040000
X360000
Y1020000
X380000
X360000Y1000000
X380000
X360000Y980000
X380000
X360000Y960000
X380000
Y940000
X360000
X380000Y920000
X371059Y903347
X379270Y885897
X387292
X387250Y881000
X379372Y880728
X379228Y874277
X372000Y865000
X368500
X360800Y858500
X375200Y858250
X397000Y844750
X370000Y841000
X364500
X381000
X375500
X364500Y835500
X381000
X375500
X370000
X381000Y830000
X364500
X375500
X370000
X365000Y824500
X370000
X381000
X375500
Y819000
X381000
X365000
X370000
X360100Y808080
X395000Y806500
X368700Y803750
X388250Y803300
X365500Y797000
X362000
X385250Y785700
X385196Y779112
X377250Y779000
Y774500
X385238Y774122
X360000Y720000
Y700000
Y680000
X380000Y660000
X360000
Y640000
X380000
Y620000
X360000Y580000
X380000Y560000
Y540000
Y500000
X387249Y455882
X379258Y455892
X385607Y451232
X379250Y451000
X385896Y444265
X370397Y439122
X372000Y436000
X368500
X375200Y429250
X364758Y429249
X397000Y414750
X370000Y411000
X375500
X364500
X381000
Y405500
X364500
X370000
X375500
Y400000
X370000
X364500
X381000
X375500Y394500
X365000
X370000
X381000
X375500Y389000
X381000
X370000
X365000
X397000Y383750
Y380250
X365100Y371200
X375200Y371250
X368500Y364500
X372000
X370128Y361337
X391800Y355800
X383750Y349000
Y344500
X391750
X369000Y294000
X360000Y280000
Y260000
X380000Y200000
X360000Y180000
X380000
X360000Y160000
X380000
X360000Y140000
X380000
X360750Y124000
X373500Y98000
X377500
X382000
X382200Y81500
X378100
X374300Y81400
X363750Y73300
Y65250
Y54250
X380000Y40000
X360000
X380000Y20000
X360000
X390018Y5500
X370018
X430018
X410018
X400000Y20000
X420000
Y40000
X400000
X420000Y60000
X400000
Y80000
X420000
X400000Y100000
X420000
Y120000
X400000
X420000Y140000
X400000
X420000Y160000
X400000
X420000Y180000
X400000
Y200000
X420000
X400000Y220000
X420000
Y240000
Y260000
X405500Y277500
X405000Y289000
X401500Y401500
Y410250
X410550Y420500
X400000Y440000
Y460000
Y480000
X420000Y500000
X400000Y520000
X420000
X400000Y540000
X420000
Y560000
X400000
X420000Y600000
Y620000
X400000
Y640000
X420000Y660000
Y680000
X400000
X420000Y700000
X400000
X420000Y720000
X400000
Y740000
X420000
Y760000
X400000Y780000
X420000
X425891Y812750
X421000
X420722Y820627
X425890Y820729
X414281Y820751
X401500Y836000
X420000Y840000
X404000Y840500
X402000Y844000
X410550Y850500
X420000Y860000
Y880000
X400000Y900000
X420000
Y920000
X400000
Y940000
X420000
Y960000
X400000
X420000Y980000
X400000
X420000Y1000000
X400000
X420000Y1020000
X400000
Y1040000
X420000
Y1060000
X400000
Y1080000
X420000Y1160000
Y1180000
X405500Y1192000
X420000Y1200000
X402000Y1202500
X425500Y1215250
X420743Y1215266
X420763Y1223185
X425500Y1223250
X414274Y1223246
X400700Y1237500
X408300
X420000Y1240000
X400000Y1260000
X420000
Y1280000
X400000
Y1300000
X420000
X400000Y1320000
X420000
X400000Y1340000
X420000
X400000Y1360000
X420000
X400000Y1380000
X420000
X400000Y1400000
X420000
Y1420000
X400000
X420000Y1440000
X400000
Y1460000
X420000
Y1480000
X400000Y1520000
Y1540000
X420000
Y1580000
X400000
Y1660000
X420000
Y1680000
Y1700000
X402000Y1701000
X425500Y1713750
X421000
X425879Y1721724
X414299Y1721750
X420732Y1721757
X406500Y1736500
X420000Y1760000
X400000
Y1800000
Y1820000
X420000
Y1840000
X400000
X420000Y1860000
X400000
Y1880000
X420000
X400000Y1900000
X420000
X400000Y1920000
X420000
X400000Y1940000
X420000
Y1960000
X400000
Y1980000
X420000
X412559Y1986626
X432559
X452559
X472559
X440000Y1980000
X460000
X440000Y1960000
X460000
X440000Y1940000
X460000
X440000Y1920000
X460000
X440000Y1900000
X460000
X440000Y1880000
X460000
X440000Y1860000
X460000
X440000Y1840000
X460000
X450000Y1803500
X460000Y1780000
X440000
Y1760000
X460000
Y1680000
X440000
X460000Y1660000
Y1580000
X440000
X460000Y1520000
Y1500000
X440000
X460000Y1480000
X440000
X460000Y1460000
X440000
X460000Y1440000
X440000
Y1420000
X460000
X440000Y1400000
X460000
X440000Y1380000
X460000
X440000Y1360000
X460000
X440000Y1340000
X460000
Y1320000
X440000
X460000Y1300000
X440000
X460000Y1280000
X440000
X460000Y1260000
X440000
X460000Y1240000
X440000
Y1200000
X460000
X440000Y1180000
X460000
X440000Y1160000
X460000
Y1120000
X440000
X460000Y1080000
X440000Y1040000
X460000Y1020000
X440000
Y1000000
X460000
Y980000
X440000
X460000Y960000
X440000
Y940000
X460000
Y920000
X440000
X460000Y900000
X440000
Y880000
X460000
X440000Y860000
X460000
Y840000
X440000
X460000Y820000
Y800000
Y780000
Y760000
Y720000
Y700000
Y680000
Y660000
X440000Y600000
Y580000
X460000
X440000Y540000
Y520000
X460000
Y500000
Y480000
X440000
X460000Y460000
X440000
Y440000
X460000
X440000Y420000
X460000
X440000Y400000
X460000
X440000Y380000
X460000
Y360000
X440000
X460000Y340000
X440000
Y320000
X460000
Y300000
Y280000
X440000
X460000Y260000
X440000
Y240000
X460000
Y220000
X440000
X460000Y200000
X440000
Y180000
X460000
X440000Y160000
X460000
Y140000
X440000
X460000Y120000
X440000
Y100000
X460000
X440000Y80000
X460000
X440000Y60000
X460000
Y40000
X440000
Y20000
X460000
X470018Y5500
X450018
X490018
X510018
X480000Y20000
X500000
X480000Y40000
X500000
X480000Y60000
X500000
X480000Y80000
X500000
Y100000
X480000
Y120000
X500000
Y140000
X480000
Y160000
X500000
Y180000
X480000
Y200000
X500000
Y220000
X480000
X500000Y240000
X480000
X500000Y260000
X480000Y280000
X500000
Y300000
X480000
Y320000
X500000
Y340000
X480000
X500000Y360000
X480000
Y380000
X500000Y400000
X480000
X500000Y420000
X480000
Y440000
X500000
Y460000
X480000
Y480000
X500000
X480000Y500000
X500000
Y540000
X480000Y560000
X500000Y580000
Y600000
Y640000
X480000
X500000Y660000
X480000
Y680000
X500000
Y700000
X480000
Y720000
X500000
Y760000
X480000
Y780000
X500000
X480000Y800000
X500000
Y820000
X480000
Y840000
X500000
Y860000
X480000
X500000Y880000
X480000
Y900000
X500000
Y920000
X480000
Y940000
X500000
Y960000
X480000
X500000Y980000
X480000
Y1000000
X500000Y1040000
X480000Y1060000
X500000
Y1080000
X480000
X500000Y1120000
X480000
X500000Y1160000
X480000
X500000Y1180000
X480000
Y1200000
X500000
Y1240000
X480000
X500000Y1260000
X480000
Y1280000
X500000
X480000Y1300000
X500000
X480000Y1320000
X500000
Y1340000
X480000
X500000Y1360000
X480000
X500000Y1380000
X480000
X500000Y1400000
X480000
X500000Y1420000
X480000
X500000Y1440000
X480000
Y1460000
X500000
X480000Y1480000
X500000
X480000Y1500000
X500000
X480000Y1520000
X500000
Y1560000
X480000Y1580000
X500000Y1660000
X480000
X500000Y1680000
X480000
Y1700000
X500000
Y1720000
X480000
X500000Y1740000
X480000
Y1760000
X500000
Y1780000
X480000
X500000Y1820000
X480000
X500000Y1840000
X480000Y1860000
X500000Y1880000
X480000
X500000Y1900000
X480000
Y1920000
X500000
X480000Y1940000
X500000
Y1960000
X480000
X500000Y1980000
X480000
X492559Y1986626
X512559
X532559
X552559
X520000Y1980000
X540000
X520000Y1960000
X540000
X520000Y1940000
X540000
X520000Y1920000
X540000
Y1900000
X520000
X540000Y1880000
X520000
Y1860000
X540000
X520000Y1840000
X540000
X520000Y1820000
X540000
Y1780000
X520000
X540000Y1760000
X520000
X540000Y1740000
X520000
Y1720000
X540000
X520000Y1700000
X540000
Y1680000
X520000
Y1660000
X540000
X547659Y1566037
X542159
X547659Y1560537
X542159
X540000Y1520000
X520000
X540000Y1500000
X520000
X540000Y1480000
X520000
Y1460000
X540000
Y1440000
X520000
X540000Y1420000
X520000
Y1400000
X540000
X520000Y1380000
X540000
Y1360000
X520000
Y1340000
X540000
Y1320000
X520000
X540000Y1300000
X520000
X540000Y1280000
X520000
Y1260000
X540000Y1220000
X520000Y1200000
X540000
Y1180000
X520000
X540000Y1160000
X520000
Y1120000
X540000
Y1100000
X520000Y1080000
X540000Y1060000
X520000
X540000Y1040000
X520000
X540000Y980000
X520000
X540000Y960000
X520000
Y940000
X540000
Y920000
X520000
X540000Y900000
X520000
X540000Y880000
X520000
X540000Y860000
X520000
X540000Y840000
X520000
X540000Y820000
X520000
Y800000
X540000
X520000Y780000
X540000
Y760000
X520000
X540000Y740000
X520000Y720000
Y700000
X540000
Y680000
X520000
X540000Y660000
X520000
X540000Y640000
X520000
Y600000
X540000
Y580000
X520000
X540000Y560000
X520000
X540000Y540000
X520000Y520000
Y480000
X540000Y460000
X520000
Y440000
X540000
Y420000
X520000
X540000Y400000
X520000
X540000Y380000
X520000
Y360000
X540000
X520000Y340000
X540000
Y320000
X520000
Y300000
X540000
Y280000
X520000
X540000Y260000
X520000
Y240000
X540000
X520000Y220000
X540000
Y200000
X520000
Y180000
X540000
Y160000
X520000
Y140000
X540000
X520000Y120000
X540000
X520000Y100000
X540000
Y80000
X520000
X540000Y60000
X520000
X540000Y40000
X520000
X540000Y20000
X520000
X530018Y5500
X550018
X590018
X570018
X560000Y20000
X580000
X560000Y40000
X580000
Y60000
X560000
X580000Y80000
X560000
Y100000
X580000
Y120000
X560000
Y140000
X580000
Y160000
X560000
X580000Y180000
X560000
X580000Y200000
X560000
Y220000
X580000
X560000Y240000
X580000
X560000Y260000
X580000
X560000Y280000
X580000
X560000Y300000
X580000
Y320000
X560000
Y340000
X580000
X560000Y360000
X580000
Y380000
X560000
Y400000
X580000
Y420000
X560000
X580000Y440000
X560000
Y460000
X580000Y500000
Y520000
Y540000
X560000
X580000Y560000
X560000
X580000Y580000
X560000
X580000Y600000
X560000Y640000
X580000
X560000Y660000
X580000
Y680000
X560000
Y700000
X580000
X560000Y740000
X580000
X560000Y760000
X580000
Y780000
X560000
X580000Y800000
X560000
X580000Y820000
Y840000
X560000
Y860000
X580000
Y880000
X560000
Y900000
X580000
X560000Y920000
X580000
Y940000
X560000
X580000Y960000
X560000
Y980000
X580000
Y1040000
X560000
X580000Y1060000
X560000
Y1100000
X580000
X560000Y1120000
X580000
Y1160000
Y1180000
X560000
Y1200000
X580000
X560000Y1220000
X580000
Y1240000
X560000
X580000Y1260000
X560000Y1300000
Y1320000
X580000
X560000Y1340000
X580000
Y1360000
Y1380000
X560000
X580000Y1400000
X560000
Y1420000
X580000
Y1440000
X560000
X580000Y1460000
X560000
Y1480000
X580000
Y1500000
X560000
X580000Y1520000
X560000
X580000Y1660000
X560000
X580000Y1680000
X560000
X580000Y1700000
X560000
X580000Y1720000
X560000
Y1740000
X580000
Y1760000
X560000
X580000Y1780000
X560000
X580000Y1800000
X560000
Y1840000
X580000
X560000Y1860000
X580000
Y1880000
X560000
Y1900000
X580000
X560000Y1920000
X580000
Y1940000
X560000
Y1960000
X580000
X560000Y1980000
X580000
X572559Y1986626
X592559
X612559
X632559
X620000Y1980000
X600000
Y1960000
X620000
Y1940000
X600000
Y1920000
X620000
X600000Y1900000
X620000
X600000Y1880000
X620000
X600000Y1860000
X620000
X600000Y1840000
X620000
X600000Y1800000
X620000
X600000Y1780000
X620000
Y1760000
X600000
X620000Y1740000
X600000
Y1720000
X620000
X600000Y1700000
X620000
X600000Y1680000
X620000
Y1660000
X600000
X634200Y1565700
X639700
Y1561200
X634200
X620000Y1500000
X600000
X620000Y1480000
X600000
Y1460000
X620000
X600000Y1440000
X620000
X600000Y1420000
X620000
X600000Y1400000
X620000
Y1380000
Y1360000
X600000
Y1340000
X620000Y1300000
Y1280000
Y1260000
X600000
X620000Y1240000
X600000
Y1220000
X620000
Y1200000
X600000
Y1180000
X620000
X600000Y1160000
X620000
Y1120000
X600000
Y1100000
X620000
X600000Y1060000
X620000
X600000Y1040000
X620000
X600000Y980000
X620000
Y960000
X600000
X620000Y940000
X600000
Y920000
X620000
Y900000
X600000
X620000Y880000
X600000
Y860000
X620000
Y840000
X600000
Y820000
X620000
Y800000
X600000
X620000Y780000
X600000
Y760000
X620000
Y740000
X600000
X620000Y700000
X600000
X620000Y680000
X600000
X620000Y660000
X600000
Y640000
X620000
X600000Y600000
X620000
X600000Y580000
X620000
Y560000
X600000
X620000Y540000
X600000
X620000Y520000
X600000
Y500000
X620000
X600000Y480000
X620000
Y460000
Y420000
X600000
Y400000
X620000
X600000Y380000
X620000
Y360000
X600000
Y340000
X620000
X600000Y320000
X620000
X600000Y300000
X620000
X600000Y280000
X620000
X600000Y260000
X620000
Y240000
X600000
Y220000
X620000
X600000Y200000
X620000
Y180000
X600000
Y160000
X620000
Y140000
X600000
X620000Y120000
X600000
X620000Y100000
X600000
Y80000
X620000
Y60000
X600000
Y40000
X620000
X600000Y20000
X620000
X630018Y5500
X610018
X670018
X650018
X640000Y20000
X660000
Y40000
X640000
X660000Y60000
X640000
Y80000
X660000
X640000Y100000
X660000
Y120000
X640000
Y140000
X660000
Y160000
X640000
Y180000
X660000
Y200000
X640000
Y220000
X660000
X640000Y240000
X660000
Y260000
X640000
Y280000
X660000
Y300000
X640000
Y320000
X660000
X640000Y340000
X660000
X640000Y360000
X660000
X640000Y380000
X660000
X640000Y400000
Y440000
X660000
Y460000
X640000
Y480000
X660000
X640000Y500000
X660000
Y520000
X640000
X663000Y535500
X660000Y540000
X640000
Y560000
X660000
Y580000
X640000
Y600000
X660000
Y640000
X640000
X661500Y650500
X660000Y660000
X640000
X660000Y680000
X640000
Y700000
X660000Y720000
X640000
X660000Y740000
X640000
Y760000
X660000
Y780000
X640000
Y800000
X660000
Y820000
X640000
X662000Y826600
X660000Y840000
X640000
X660000Y860000
X640000
Y880000
X660000
X640000Y900000
X660000
X640000Y920000
X660000
X665000Y937000
X640000Y940000
Y960000
X660000
Y980000
X640000
X660000Y1040000
X640000
X660000Y1053500
X640000Y1060000
X660000Y1100000
X640000
Y1120000
X660000
Y1160000
X640000
Y1180000
X662000Y1183500
X640000Y1200000
X660000
Y1220000
X640000
X660000Y1240000
X640000
X660000Y1260000
X640000
X660000Y1280000
X640000
X660000Y1300000
X640000
X660000Y1320000
X640000
X657000Y1331500
X660000Y1340000
X640000Y1380000
Y1400000
X660000
Y1420000
X640000
X660000Y1440000
X640000
X662000Y1459000
X640000Y1460000
Y1480000
X660000
Y1500000
X640000
X651700Y1561200
X646200
X651700Y1565700
X646200
X660000Y1660000
X640000
Y1680000
X660000
Y1700000
X640000
Y1720000
X660000
Y1740000
X640000
X660000Y1760000
X640000
X660000Y1780000
X640000
X660000Y1800000
X640000
X660000Y1820000
X640000Y1840000
X660000
X640000Y1860000
X660000
Y1880000
X640000
Y1900000
X660000
X640000Y1920000
X660000
Y1940000
X640000
X660000Y1960000
X640000
Y1980000
X660000
X652559Y1986626
X672559
X692559
X712559
X700000Y1980000
X680000
X700000Y1960000
X680000
X700000Y1940000
X680000Y1920000
X700000
X680000Y1900000
X700000
X680000Y1880000
X700000
Y1860000
X680000
Y1820000
X700000
Y1800000
X680000
X700000Y1780000
X680000
Y1760000
X700000
Y1740000
X680000
Y1720000
X700000Y1680000
X680000
X700000Y1500000
X680000
Y1480000
X700000
Y1440000
X680000
Y1420000
X700000Y1380000
X680000Y1360000
X700000
X680000Y1340000
X700000
Y1320000
X680000
Y1300000
X700000
X680000Y1280000
X700000
X680000Y1260000
X700000
X680000Y1240000
X700000
X680000Y1220000
X700000
Y1200000
X680000
X700000Y1160000
X680000
Y1120000
X700000
X680000Y1100000
X700000
Y1080000
X680000
Y1040000
X700000
Y980000
X680000
X700000Y960000
X680000
X700000Y920000
X680000
Y900000
X700000
X680000Y880000
X700000
Y860000
X680000
X700000Y840000
X680000
X700000Y820000
X680000
Y800000
X700000
X680000Y780000
X700000
X680000Y760000
X700000
X680000Y740000
X700000
X680000Y720000
X700000
X680000Y680000
X700000
X680000Y660000
X700000
Y640000
X680000
X700000Y600000
X680000
Y580000
X700000
X680000Y560000
X700000
Y540000
X680000
X700000Y520000
X680000
X700000Y500000
X680000
X700000Y480000
X680000
Y460000
X700000
X680000Y440000
X700000
X680000Y420000
X700000
Y400000
X680000Y360000
Y340000
Y320000
X700000
Y300000
X680000
X700000Y280000
X680000
Y260000
X700000
X680000Y240000
X700000
Y220000
X680000
X700000Y200000
X680000
Y180000
X700000
Y160000
X680000
Y140000
X700000
X680000Y120000
X700000
Y100000
X680000
Y80000
X700000
X680000Y60000
X700000
X680000Y40000
Y20000
X700000
X710018Y5500
X690018
X730018
X750018
X740000Y20000
X720000
X740000Y40000
X720000Y60000
X740000
Y80000
X720000
Y100000
X740000
X720000Y120000
X740000
X720000Y140000
X740000
Y160000
X720000
X740000Y180000
X720000
Y200000
X740000
X720000Y220000
X740000
Y240000
X720000
Y260000
X740000
X720000Y280000
X740000
X720000Y300000
X740000
X720000Y320000
X740000Y380000
X720000
X740000Y400000
X720000
Y420000
X740000
Y440000
X720000
Y460000
X740000
X720000Y480000
X740000
Y500000
X720000
X740000Y520000
X720000
Y540000
X740000
X720000Y560000
X740000
X720000Y580000
X740000
Y600000
X720000
X740000Y620000
X720000
Y640000
X740000
X720000Y660000
X740000
X720000Y680000
X740000
X720000Y720000
X740000
Y740000
X720000
X740000Y760000
X720000
Y780000
X740000
Y800000
X720000
Y820000
X740000
X720000Y840000
X740000
X720000Y860000
X740000
Y880000
X720000
X740000Y900000
X720000
Y920000
X740000
X720000Y960000
X740000
Y980000
X720000
X740000Y1040000
X720000
X740000Y1080000
Y1120000
X720000
X740000Y1160000
X720000
Y1200000
X740000
Y1220000
X720000
X740000Y1240000
X720000
X740000Y1260000
X720000
Y1280000
X740000
X720000Y1300000
X740000
Y1320000
X720000
X740000Y1340000
X720000
Y1360000
X740000
X720000Y1380000
X740000
Y1420000
X720000
Y1440000
X740000
X720000Y1480000
X740000
Y1520000
X720000
X753500Y1662000
X759000
Y1666500
X753500
X740000Y1680000
X720000
Y1700000
X740000
Y1720000
X720000
X740000Y1740000
X758000Y1756000
X720000Y1780000
Y1800000
X740000
X759700Y1817500
X720000Y1820000
X740000
X759700Y1837500
X720000Y1860000
X740000
Y1880000
X720000
Y1900000
X740000
X720000Y1920000
X728700Y1933100
X720000Y1940000
X759900Y1959200
X720000Y1960000
X740000
X755995Y1968282
X720000Y1980000
X740000
X732559Y1986626
X752559
X792559
X772559
X780000Y1980000
X760000
X785239Y1960907
X799205Y1960532
X797239Y1956807
X769239Y1955776
X774989Y1955708
X797239Y1953307
X780214Y1953257
X796339Y1940507
X760000Y1940000
X796339Y1937007
X780000Y1920000
X760000Y1880000
X780000Y1840000
Y1800000
Y1780000
X760000
X795500Y1755000
X780000Y1740000
X760000
Y1720000
X765500Y1666500
X771000
Y1662000
X765500
X780000Y1520000
X760000
X780000Y1480000
X760000
Y1440000
X780000
Y1420000
X760000
X780000Y1380000
X760000
X780000Y1360000
X760000
Y1340000
X780000
X760000Y1320000
X780000
X760000Y1300000
X780000
Y1280000
X760000
Y1260000
X780000
X760000Y1240000
X780000
Y1220000
X760000
X780000Y1200000
X760000
Y1160000
X780000
X760000Y1120000
X780000
Y1060000
X760000Y1040000
X780000Y980000
X760000
X780000Y960000
X760000
Y920000
X780000
Y900000
X760000
X780000Y880000
X760000
Y860000
X780000
Y840000
X760000
Y820000
X780000Y800000
X760000
X780000Y780000
X760000
X780000Y760000
X760000
X780000Y740000
X760000
Y720000
X780000
Y700000
X760000Y680000
X798400Y659800
X778400
X782500Y648000
X760000Y640000
X780000
Y620000
X760000
Y600000
X780000
X760000Y580000
X780000
X760000Y560000
X780000
X760000Y540000
X780000
Y520000
X760000
Y500000
X780000
X760000Y480000
X780000
Y460000
X760000
Y440000
X780000
X760000Y420000
X780000
X760000Y400000
X780000
X760000Y380000
X780000
Y360000
X760000
X780000Y340000
X760000Y320000
X780000Y300000
X760000Y280000
Y260000
Y240000
X780000
Y220000
X760000
Y200000
X780000
X792343Y197402
Y193599
X760000Y180000
X780000
Y160000
X760000
X780000Y140000
X760000
X780000Y120000
X760000
X780000Y100000
X760000
Y80000
X780000
Y60000
X760000
X780000Y40000
X760000
X780000Y20000
X760000
X790018Y5500
X770018
X810018
X830018
X800000Y20000
X820000
X800000Y40000
X820000
Y60000
X800000
Y80000
X820000
Y100000
X800000
Y120000
X820000
X800000Y140000
X820000
X832500Y171000
X824500
X820500
X816500
X828500
X816000Y187000
X828000Y203000
X820000Y220000
X800000
Y240000
X820000Y260000
X800000Y280000
Y340000
Y360000
X833000Y362500
X836500
X815375Y362750
X824335Y365915
X836500Y366000
X833000
X813350Y369250
X800000Y380000
Y400000
X820000
X800000Y420000
X820000
Y440000
X800000
X820000Y460000
X800000
X820000Y480000
X800000
Y500000
X820000
Y520000
X800000
Y540000
X820000
Y560000
X800000
X820000Y580000
X800000
Y600000
X820000
Y620000
X800000
Y640000
X820000Y660000
Y700000
X800000Y720000
X820000
X800000Y740000
Y760000
X836500Y768000
X833000
X815375Y768250
X824335Y771415
X836500Y771500
X833000
X800000Y780000
X820000Y820000
Y840000
X800000
Y860000
X820000
X800000Y880000
X820000
Y900000
X800000
Y920000
X820000
Y960000
X800000
Y980000
X820000
Y1040000
X800000Y1060000
X820000
X800000Y1080000
Y1100000
Y1120000
X820000
X800000Y1160000
X815375Y1173750
X824335Y1176915
X836500Y1177000
X833000
X800000Y1200000
X820000
X800000Y1220000
X820000
Y1240000
X800000
X820000Y1260000
X800000
X820000Y1280000
X800000
Y1300000
X820000
Y1320000
X800000
X820000Y1340000
X800000
Y1360000
X820000
X800000Y1380000
X820000
Y1420000
X800000
X820000Y1440000
X800000
X820000Y1480000
X800000
Y1560000
X836500Y1579000
X833000
X816625Y1579250
X824335Y1582415
X833000Y1582500
X836500
X813000Y1585750
X814000Y1621500
X808500
X814000Y1626000
X808500
X814000Y1630500
X808500
X820000Y1680000
X837388Y1695500
X825388
X833388
X829388
X833388Y1739500
X825388
X829388
X837388
X800000Y1740000
Y1780000
X829500Y1785000
X819000
X815000
X837500
X800000Y1800000
X816000Y1801000
X827500Y1817000
X820000Y1820000
X800000
X834750Y1823285
X819000Y1839000
X828000Y1862000
X800000Y1920000
X820000
X804239Y1953307
X800739
X804239Y1956807
X800739
X827900Y1973400
X823400
X839400Y1973500
X835900
X800000Y1980000
X820000
X812559Y1986626
X832559
X852559
X872559
X860000Y1980000
X840000
X843500Y1973500
X847000
X879500Y1970000
X862000Y1969900
Y1960500
X858800Y1951300
X844800Y1949700
X844700Y1945200
X876441Y1940906
X872941Y1938382
Y1933982
X876441Y1931457
X863346Y1929650
X867441Y1928333
Y1925133
X863346Y1923816
X876441Y1922008
X872941Y1919484
Y1915084
X876441Y1912559
X863441Y1911020
X867441Y1909435
Y1906235
X863441Y1904650
X876441Y1903111
X872941Y1900586
Y1896186
X876441Y1893662
X863287Y1891650
X867441Y1890538
Y1887338
X863287Y1886226
X876441Y1884213
X860000Y1880000
X876441Y1877914
X867500Y1870000
X876441Y1868465
X876000Y1864000
X860000Y1860000
X876441Y1859016
Y1852717
X872941Y1850193
Y1845793
X876441Y1843268
X863441Y1841938
X867441Y1840144
Y1836944
X863441Y1835150
X876441Y1833819
X865125Y1751800
X872875Y1751600
X859500Y1696000
X841388Y1695500
X873962Y1685500
Y1681500
X840000Y1680000
X873962Y1676500
Y1672000
X860000Y1660000
X840000
X877853Y1654249
Y1650749
X860000Y1640000
X840000
Y1600000
X865500Y1589000
X873000
X876500
X869000
X850966Y1586525
X843500Y1582500
X840000
X860000Y1580000
X843500Y1579000
X840000
X845600Y1554300
X855500
X859500Y1553200
Y1549700
X873300Y1549100
X876441Y1535394
X872941Y1532870
Y1528470
X876441Y1525945
X863347Y1524138
X867441Y1522821
Y1519621
X863347Y1518304
X876441Y1516496
X872941Y1513972
Y1509572
X876441Y1507047
X863441Y1505508
X867441Y1503923
Y1500723
X863441Y1499138
X876441Y1497599
X872941Y1495074
Y1490674
X876441Y1488150
X863286Y1486138
X867441Y1485026
Y1481826
X863286Y1480714
X840000Y1480000
X876441Y1478701
Y1472402
X868500Y1465000
X876441Y1462953
X876500Y1459000
X876441Y1453504
Y1447205
X872941Y1444681
Y1440281
X840000Y1440000
X860000
X876441Y1437756
X863441Y1436426
X867441Y1434632
Y1431432
X863441Y1429638
X876441Y1428307
X840000Y1420000
X860000
Y1380000
X840000
X857688Y1364488
X840000Y1360000
X872875Y1346488
X865125
X860000Y1340000
X840000
Y1320000
X860000
Y1300000
X840000
X860000Y1280000
X840000
X860000Y1260000
X840000
Y1240000
X860000
X840000Y1220000
X860000
X840000Y1200000
X860000
X864000Y1181900
X867500
X872200
X875700
X850600Y1181025
X843500Y1177000
X840000
X844600Y1148700
X854500
X859500Y1147600
Y1144100
X874200Y1144000
X876441Y1129882
X872941Y1127358
Y1122958
X876441Y1120433
X863346Y1118626
X867441Y1117309
Y1114109
X863346Y1112792
X876441Y1110984
X872941Y1108460
Y1104060
X876441Y1101535
X863441Y1099996
X867441Y1098411
Y1095211
X863441Y1093626
X876441Y1092087
X872941Y1089562
Y1085162
X876441Y1082638
X863308Y1080702
X867441Y1079514
Y1076314
X863308Y1075126
X876441Y1073189
Y1066890
X840000Y1060000
X868500Y1059500
X876441Y1057441
X876500Y1053500
X876441Y1047992
Y1041693
X840000Y1040000
X860000
X872941Y1039169
Y1034769
X876441Y1032244
X863441Y1030914
X867441Y1029120
Y1025920
X863441Y1024126
X876441Y1022795
X840000Y980000
X860000
X840000Y960000
X857623Y958977
X865125Y949600
X872875Y940925
X840000Y920000
X860000
Y900000
X840000
Y880000
X860000
X840000Y860000
X860000
Y840000
X840000
Y820000
X860000
X840000Y800000
X860000
X872000Y776500
X864500
X868000
X875500
X850966Y775525
X840000Y771500
X843500
Y768000
X840000
X856100Y743300
X846200
X859500Y741800
X873400Y738400
X859500Y738300
X876441Y724370
X872941Y721846
X840000Y720000
X872941Y717446
X876441Y714921
X863397Y713280
X867441Y711797
Y708597
X863397Y707114
X876441Y705472
X872941Y702948
X840000Y700000
X872941Y698548
X876441Y696023
X863441Y694484
X867441Y692899
Y689699
X863441Y688114
X876441Y686575
X872941Y684050
X840000Y680000
X872941Y679650
X876441Y677126
X863287Y675114
X867441Y674002
Y670802
X863287Y669690
X876441Y667677
Y661378
X840000Y660000
X868500Y654000
X876441Y651929
X876500Y648000
X876441Y642480
X840000Y640000
X876441Y636181
X872941Y633657
Y629257
X876441Y626732
X863441Y625402
X867441Y623608
Y620408
X840000Y620000
X863441Y618614
X876441Y617283
X860000Y600000
X840000
Y580000
X860000
X840000Y560000
X860000
X857735Y553465
X865125Y544000
X840000Y540000
X872875Y535275
X860000Y520000
X840000
Y500000
X860000
Y480000
X840000
Y460000
X860000
Y440000
X840000
X860000Y420000
X840000
Y400000
X860000
X879600Y385200
X868500Y371000
X865000
X872500
X876000
X850966Y370025
X840000Y366000
X843500
Y362500
X840000
X856200Y337300
X844050
X860100Y336500
Y333000
X873600Y332200
X876441Y318858
X872941Y316334
Y311934
X876441Y309409
X863346Y307602
X867441Y306285
Y303085
X863346Y301768
X876441Y299960
X872941Y297436
Y293036
X876441Y290511
X863441Y288972
X867441Y287387
Y284187
X863441Y282602
X876441Y281063
X872941Y278538
Y274138
X876441Y271614
X863307Y269678
X867441Y268490
Y265290
X863307Y264102
X876441Y262165
X860000Y260000
X876441Y255866
X876500Y251000
X876441Y246417
X872500Y241500
X860000Y240000
X840000
X876441Y236968
Y230669
X872941Y228145
Y223745
X876441Y221220
X863441Y219890
X867441Y218096
Y214896
X863441Y213102
X876441Y211771
X844000Y190000
X840000Y174250
X866961Y162539
X864975Y148875
X869250Y144750
X840000Y140000
X860000
Y120000
X840000
X860000Y100000
X840000
X860000Y80000
X840000
Y60000
X860000
X840000Y40000
X860000
Y20000
X840000
X870018Y5500
X850018
X910018
X890018
X880000Y20000
X900000
X880000Y40000
X900000
X880000Y60000
X900000
X880000Y80000
X900000
X880000Y100000
X900000
X880000Y120000
X900000
X885993Y134893
X908493Y136513
X896441Y147203
X896547Y150803
X885531Y164804
X890469
X880000Y180000
X899941Y203917
Y218917
X904838Y231105
X908654
X899941Y233917
X905146Y235394
X908346
X918846Y238501
Y241701
X901441Y244842
X901600Y249800
X899941Y278917
Y283917
Y308917
X901500Y312500
X899900Y382300
X880000Y400000
X900000
Y420000
X880000
X900000Y440000
X880000
Y460000
X900000
Y480000
X880000
X900000Y500000
X880000
X900000Y520000
X880000
X891250Y537500
X907493Y542025
X895547Y552715
Y556315
X883781Y564519
X888719
X880000Y580000
Y600000
X900000
X899941Y609429
Y624429
X908654Y636613
X904838
X899941Y639429
X919000Y639715
X905146Y640906
X908346
X918846Y644013
Y647213
X901441Y650354
X919000Y651511
X901200Y655100
X899941Y684429
Y689429
Y714429
X901500Y718000
X880000Y800000
X900000
Y820000
X880000
Y840000
X900000
X880000Y860000
X900000
X880000Y880000
X900000
X880000Y900000
X900000
X880000Y920000
X900000
X886517Y945917
X907493Y947537
X895547Y958227
Y961827
X883781Y970031
X888719
X900000Y1000000
X880000
X899941Y1014941
X900000Y1020000
X899941Y1029941
X900000Y1040000
X908654Y1042129
X904838
X899941Y1044941
X908346Y1046418
X905146
X918846Y1049525
Y1052725
X901441Y1055866
X901300Y1060700
X900000Y1080000
X899941Y1089941
Y1094941
Y1119941
X901500Y1123500
X880000Y1200000
X900000
Y1220000
X880000
X900000Y1240000
X880000
X900000Y1260000
X880000
X900000Y1280000
X880000
Y1300000
X900000
X880000Y1320000
X900000
X880000Y1340000
X891250Y1348500
X907493Y1353048
X895647Y1363738
Y1367338
X887438Y1373374
X883219Y1373504
X899941Y1420453
Y1435453
X908654Y1447641
X904838
X899941Y1450453
X919000Y1450734
X908346Y1451930
X905146
X918846Y1455037
Y1458237
X901441Y1461378
X919000Y1462540
X901400Y1466100
X899941Y1495453
Y1500453
Y1525453
X901500Y1529000
X880000Y1599000
X900000Y1600000
X881353Y1650749
Y1654249
X896500Y1681000
X901500Y1681500
X915250Y1687500
X885750Y1701500
X895500Y1708000
X891500
X919250Y1711500
X895500Y1712000
X891500
X906000Y1713500
X891000Y1720000
X910500Y1724700
X916500Y1729500
X898500Y1734000
X902500
X906500Y1734100
X910500Y1734600
X886600Y1756100
X907493Y1758560
X895547Y1769250
Y1772850
X883781Y1781054
X888719
X899941Y1825965
Y1840965
X904838Y1853153
X908654
X899941Y1855965
X919000Y1856251
X905146Y1857442
X908346
X918846Y1860549
Y1863749
X901441Y1866890
X919000Y1868047
X901200Y1871600
X899941Y1900965
Y1905965
Y1930965
X901500Y1934500
X880000Y1955500
X912559Y1986626
X896546Y1986566
X952559Y1986626
X932559
X920000Y1980000
X940000
X920000Y1960000
X940000
Y1940000
X920000
Y1920000
X940000
Y1900000
X920000
X940000Y1880000
X920000
X940000Y1860000
Y1840000
X920000
X940000Y1820000
X920000Y1800000
X940000
X926400Y1786500
Y1782000
Y1777500
X940000Y1760000
X925500Y1738000
X933000Y1736500
X921900Y1722400
X933000Y1704000
X934825Y1682285
X952000Y1678000
X959000Y1675000
X926500Y1660000
X931000Y1659000
X951500Y1658000
X959000Y1657000
X947000Y1654500
X941000Y1653000
X943500Y1646989
X959000Y1631000
X920000Y1600000
X923500Y1579800
X923800Y1559300
X920000Y1540000
Y1520000
Y1480000
Y1440000
X954300Y1412600
X940000Y1400000
X920000
X926300Y1380988
Y1376500
Y1372000
X940000Y1340000
X920000
Y1320000
X940000
Y1300000
X920000
X940000Y1280000
X920000
X940000Y1260000
X920000
X940000Y1240000
X920000
Y1220000
X940000
X920000Y1200000
X940000
X923000Y1180200
X940000Y1180000
X923000Y1160200
X940000Y1160000
Y1140000
X920000
Y1120000
X940000
Y1100000
Y1080000
X920000
Y1060000
X940000
X922900Y1054200
Y1048050
X920000Y1040000
X940000
Y1020000
X920000
Y1000000
X940000
X926477Y975477
Y971000
Y966500
X940000Y940000
X920000Y920000
X940000
Y900000
X920000
Y880000
X940000
Y860000
X920000
Y840000
X940000
Y820000
X920000
X940000Y800000
X920000
Y780000
X940000
Y760000
X920000
Y740000
X940000
X920000Y720000
X940000
Y700000
X920000
X940000Y680000
X920000
X940000Y660000
X920000
X940000Y640000
Y620000
X920000Y600000
X940000
Y580000
X920000
X926365Y569965
Y565500
Y561000
X940000Y520000
X920000
X940000Y500000
X920000
Y480000
X940000
Y460000
X920000
X940000Y440000
X920000
X940000Y420000
X920000
X940000Y400000
X920000
X940000Y380000
X920000
X940000Y360000
X920000
X940000Y340000
X920000
X940000Y320000
X920000
X940000Y300000
X920000
X940000Y280000
X920000
X940000Y260000
X921400Y245200
X940000Y240000
X921400Y235002
X940000Y220000
Y200000
Y180000
X926347Y164453
Y160000
X940000
X926347Y155500
X940000Y140000
Y120000
X920000
X940000Y100000
X920000
X940000Y80000
X920000
Y60000
X940000
Y40000
X920000
X940000Y20000
X920000
X930018Y5500
X950018
X990018
X970018
X980000Y20000
X960000
Y40000
X980000
X960000Y60000
X980000
Y80000
X960000
Y100000
X980000
Y120000
X960000
Y140000
Y160000
Y180000
X980000
X960000Y200000
X980000
X960000Y220000
X980000
Y240000
X960000
X980000Y260000
X960000
Y280000
X980000
X960000Y300000
X980000
X960000Y320000
X980000
Y340000
X960000
Y360000
X980000
Y380000
X960000
X980000Y400000
X960000
X980000Y420000
X960000
Y440000
X980000
Y460000
X960000
X980000Y480000
X960000
X980000Y500000
X960000
Y520000
X980000
Y540000
X960000
Y560000
X980000
Y580000
X960000
Y600000
X980000
X960000Y620000
X980000
Y640000
X960000
X980000Y660000
X960000
Y680000
X980000Y700000
X960000
X980000Y720000
X960000
Y740000
X980000
Y760000
X960000
X980000Y780000
X960000
X980000Y800000
X960000
X980000Y820000
X960000
X980000Y840000
X960000
X980000Y860000
X960000
X980000Y880000
X960000
X980000Y900000
X960000
Y920000
X980000
X960000Y940000
X980000
X960000Y960000
X980000
X960000Y980000
X980000
Y1000000
X960000
X980000Y1020000
X960000
Y1040000
X980000
X960000Y1060000
X979962Y1075211
X960000Y1080000
Y1100000
X980000
X999922Y1102598
X980000Y1120000
X960000
Y1140000
X980000
Y1160000
X960000
Y1180000
X980000
Y1200000
X960000
X980000Y1220000
X960000
Y1240000
X980000
X960000Y1260000
X980000
X960000Y1280000
X980000
X960000Y1300000
X980000
Y1320000
X960000
X980000Y1340000
X960000
X980000Y1360000
X960000
Y1380000
X980000
X960000Y1400000
X980000
X986200Y1409000
X963500
X977500
X968000
X981700
X973000
X990300Y1412500
X994600Y1414100
X991602Y1622500
X992500Y1636000
X973000Y1641500
X994898Y1646102
X995000Y1656102
X963500Y1657000
X995000Y1666102
X963500Y1675000
X995102Y1676102
X980000Y1700000
X960000
X980000Y1720000
X960000
Y1740000
X980000
X960000Y1760000
X980000
X960000Y1780000
X980000
Y1800000
X960000
Y1820000
X980000
Y1840000
X960000
Y1860000
X980000
X960000Y1880000
X980018Y1897856
X960000Y1900000
Y1920000
X980000
X999469Y1923465
X960000Y1940000
X980000
X960000Y1960000
X980000
Y1980000
X960000
X992559Y1986626
X972559
X1012559
X1031902Y1985969
X1020000Y1980000
X1000000
X1031902Y1965969
X1000000Y1960000
X1020000
X1031902Y1945969
X1000000Y1940000
X1020000
X1031902Y1925969
X1020000Y1920000
X1031902Y1905969
X1020000Y1900000
X1031902Y1885969
X1020000Y1880000
X1031902Y1865969
X1000000Y1860000
X1020000
X1031902Y1845969
X1000000Y1840000
X1020000
X1031902Y1825969
X1020000Y1820000
X1000000
X1031902Y1805969
X1020000Y1800000
X1000000
X1031902Y1785969
X1020000Y1780000
X1000000
X1031902Y1765969
X1020000Y1760000
X1000000
X1031902Y1745969
X1000000Y1740000
X1020000
X1031902Y1725969
X1000000Y1720000
X1020000
X1000000Y1700000
Y1400000
X1020000
X1031902Y1383616
X1000000Y1380000
X1020000
X1031902Y1363616
X1000000Y1360000
X1020000
X1031902Y1343616
X1000000Y1340000
X1020000
X1031902Y1323616
X1020000Y1320000
X1000000
X1031902Y1303616
X1000000Y1300000
X1020000
X1031902Y1283616
X1020000Y1280000
X1000000
X1031902Y1263616
X1020000Y1260000
X1000000
X1031902Y1243616
X1000000Y1240000
X1020000
X1031902Y1223616
X1000000Y1220000
X1020000
X1031902Y1203616
X1020000Y1200000
X1000000
X1031902Y1183616
X1020000Y1180000
X1000000
X1031902Y1163616
X1000000Y1160000
X1020000
X1031902Y1143616
X1020000Y1140000
X1000000
X1031902Y1123616
X1000000Y1120000
X1020000
X1031902Y1103616
X1020000Y1100000
X1031902Y1083616
X1020000Y1080000
X1031902Y1063616
X1020000Y1060000
X1031902Y1043616
X1000000Y1040000
X1020000
X1031902Y1023616
X1020000Y1020000
X1000000
X1031902Y1003616
X1000000Y1000000
X1020000
X1031902Y983616
X1000000Y980000
X1020000
X1031902Y963616
X1000000Y960000
X1020000
X1031902Y943616
X1020000Y940000
X1000000
X1031902Y923616
X1020000Y920000
X1000000
X1031902Y903616
X1020000Y900000
X1000000
X1031902Y883616
X1000000Y880000
X1020000
X1031902Y863616
X1000000Y860000
X1020000
X1031902Y843616
X1020000Y840000
X1000000
X1031902Y823616
X1000000Y820000
X1020000
X1031902Y803616
X1020000Y800000
X1000000
X1031902Y783616
X1000000Y780000
X1020000
X1031902Y763616
X1020000Y760000
X1000000
X1031902Y743616
X1020000Y740000
X1000000
X1031902Y723616
X1020000Y720000
X1000000
X1031902Y703616
X1020000Y700000
X1031902Y683616
X1020000Y680000
X1031902Y663616
X1020000Y660000
X1031902Y643616
X1020000Y640000
X1000000
X1031902Y623616
X1000000Y620000
X1020000
X1031902Y603616
X1020000Y600000
X1000000
X1031902Y583616
X1000000Y580000
X1020000
X1031902Y563616
X1020000Y560000
X1000000
X1031902Y543616
X1020000Y540000
X1000000
X1031902Y523616
X1000000Y520000
X1020000
X1031902Y503616
X1020000Y500000
X1000000
X1031902Y483616
X1020000Y480000
X1000000
X1031902Y463616
X1020000Y460000
X1000000
X1031902Y443616
X1020000Y440000
X1000000
X1031902Y423616
X1020000Y420000
X1000000
X1031902Y403616
X1020000Y400000
X1000000
X1031902Y383616
X1000000Y380000
X1020000
X1031902Y363616
X1020000Y360000
X1000000
X1031902Y343616
X1020000Y340000
X1000000
X1031902Y323616
X1020000Y320000
X1000000
X1031902Y303616
X1020000Y300000
X1000000
X1031902Y283616
X1000000Y280000
X1020000
X1031902Y263616
X1000000Y260000
X1020000
X1031902Y243616
X1020000Y240000
X1000000
X1031902Y223616
X1020000Y220000
X1000000
X1031902Y203616
X1020000Y200000
X1000000
X1031902Y183616
X1020000Y180000
X1031902Y163616
X1020000Y160000
X1031902Y143616
X1020000Y140000
X1031902Y123616
X1020000Y120000
X1000000
X1031902Y103616
X1020000Y100000
X1000000
X1031902Y83616
X1000000Y80000
X1020000
X1031902Y63616
X1000000Y60000
X1020000
X1031902Y43616
X1000000Y40000
X1020000
X1031902Y23616
X1000000Y20000
X1020000
X1010018Y5500
X1030018
T02
X213244Y23725
X427500Y297156
X807756Y377775
X427500Y304656
X401500Y395500
X243156Y382060
X235656
X78675Y380704
X220656Y438500
X228156
X393500Y422000
X555000Y524344
Y531844
X284000Y548844
Y541344
X206700Y575000
X47500Y660500
X512656Y623500
X520156
X808256Y783275
X401500Y830000
X393500Y852000
X190844Y808200
X183344
X126221Y861250
Y853750
X25000Y988000
X27825Y995000
X45000Y1057000
X268844Y1183060
X276344
X317156Y1193440
X324656
X396637Y1176000
X402000Y1196500
X412500Y1130750
Y1138250
X807756Y1188775
X242700Y1266656
Y1259156
X163170Y1210999
X358156Y1411000
X350656
X77607Y1565391
X117387Y1536250
Y1543750
X807756Y1594275
X979500Y1669750
Y1662250
X438656Y1669000
X431156
X402000Y1695000
X379500Y1673750
X130344Y1672400
X122844
X232344Y1740000
X239844
X450656Y1743000
X458156
T03
X71200Y36900
X136100Y41200
X935000Y1425000
X945000
X953800Y1424900
X990600Y1427100
X995000Y1425000
X1005000
X984900Y1430400
X975000Y1435000
X965000
X955000
X945000
X935000
Y1445000
X945000
X955000
X965000
X975000
Y1455000
X965000
X955000
X945000
X935000
Y1465000
X945000
X955000
X965000
X975000
Y1475000
X965000
X955000
X945000
X935000
Y1485000
X945000
X955000
X965000
X975000
Y1495000
X965000
X955000
X945000
X935000
Y1505000
X945000
X955000
X965000
Y1516000
X955000
X945000
X935000
Y1525000
X945000
X955000
X965000
X975000
Y1535000
X965000
X955000
X945000
X935000
Y1545000
X945000
X955000
X965000
X975000
Y1555000
X965000
X955000
X945000
X935000
Y1565000
X945000
X955000
X965000
X975000
Y1575000
X965000
X955000
X945000
X935000
Y1585000
X945000
X955000
X965000
X975000
Y1595000
X965000
X955000
X945000
X935000
X975000Y1605000
X965000
X38317Y1804491
X34900Y1807200
X30800Y1805300
X26500Y1805200
X22100Y1802800
X22000Y1809100
X17500Y1806900
Y1801900
Y1811900
Y1816500
X22000Y1814100
X26300Y1815000
X26600Y1810600
X30800Y1810500
X35100Y1813000
X38800Y1810100
X22600Y1825200
X17500Y1827500
X22500Y1830000
Y1835000
X17500Y1832500
Y1837500
X22500Y1840000
Y1845000
X17500Y1842500
Y1847500
X12500Y1845000
Y1840000
X7600Y1855000
X12500Y1850000
Y1855000
X17500Y1857500
Y1852500
X22500Y1850000
Y1855000
Y1860000
Y1865000
X17500Y1867500
X12500Y1870000
X17500Y1872500
X22500Y1870000
T04
X123819Y17717
X125157Y22717
X128819Y26418
X138858
X142559Y22717
X143897Y17717
X987992Y163376
X989330Y168376
X992992Y172077
X1003031
X1006732Y168376
X1008070Y163376
X285630Y279528
X284292Y284528
X280591Y288229
X270552
X266890Y284528
X265552Y279528
X43504Y281496
X42166Y286496
X38465Y290197
X28426
X24764Y286496
X23426Y281496
X265552Y685030
X266890Y690030
X270552Y693731
X280591
X284292Y690030
X285630Y685030
X987992Y686998
X989330Y691998
X992992Y695699
X1003031
X1006732Y691998
X1008070Y686998
Y1082667
X1006732Y1087667
X1003031Y1091368
X992992
X989330Y1087667
X987992Y1082667
X285630Y1088573
X284292Y1093573
X280591Y1097274
X270552
X266890Y1093573
X265552Y1088573
X11615Y1922835
X12953Y1927835
X16615Y1931536
X26654
X30355Y1927835
X31693Y1922835
X265552Y1903534
X266890Y1908534
X270552Y1912235
X280591
X284292Y1908534
X285630Y1903534
X987992
X989330Y1908534
X992992Y1912235
X1003031
X1006732Y1908534
X1008070Y1903534
T05
X33469Y1029523
X269690Y1490152
T06
X133858Y17717
X998031Y163376
X275591Y279528
X33465Y281496
X275591Y685030
X998031Y686998
Y1082667
X275591Y1088573
X21654Y1922835
X275591Y1903534
X998031
T07
X82087Y28858
Y178464
Y434370
Y583976
Y839882
Y989488
Y1245394
Y1395000
Y1650906
Y1800512
X162008Y1963268
Y1813662
Y1557756
Y1408150
Y1152244
Y1002638
Y746732
Y597126
Y341220
Y191614
X890354
Y341220
Y597126
Y746732
Y1002638
Y1152244
Y1408150
Y1557756
Y1813662
Y1963268
T08
X-63741Y15000
X1010999Y43999
X1101142Y15000
X-42339Y1008909
X-63741Y1977126
X25499Y1950499
X1010499
X1101142Y1977126
T09
X11811Y571426
Y949378
Y1067489
Y1445441
Y1484811
Y1862763
T10
X1023228Y1416024
Y1694212
M30
